# T6G (Grand Teton) — schematic netlist excerpt (pin names and nets, part order shuffled) for the footprints in the layout excerpt that follows; sources: Cadence DE-HDL packaged netlist, KiCad conversion of 04192023_DAF0TMB3IC0_F0TG_MB_C_brd_V02_OCP.brd

C6577  Q_CAP_DIFFBUS  DIFF BUS_0.22UF 6.3V 20% X6S  pkg C0201  page 297 : \1\ = P5E_CPU0_P2_TX_BUF_C_DP<6> ; \2\ = P5E_CPU0_P2_TX_BUF_DP<6>
R6333  Q_RES  47K 0.1% EMPTY  pkg 0402LF  page 178 : A = USB_HUB2_TI_GRSTZ_MRP_PROG_FUNC1 ; B = GND
C5032  Q_CAP  10UF 25V 10% X6S  pkg C0805  page 187 : A = P1V5_BAT ; B = GND
C6506  Q_CAP_DIFFBUS  DIFF BUS_0.22UF 6.3V 20% X6S  pkg C0201  page 275 : \1\ = P5E_CPU0_P0_TX_BUF_C_DN<2> ; \2\ = P5E_CPU0_P0_TX_BUF_DN<2>

(kicad_pcb
	(version 20260206)
	(generator "pcbnew")
	(generator_version "10.0")
	(general
		(thickness 1.6)
		(legacy_teardrops no)
	)
	(paper "A4")
	(title_block
		(title "04192023_DAF0TMB3IC0_F0TG_MB_C_brd_V02_OCP.brd")
		(comment 1 "Grand Teton / footprints 4650-4653 of 8354")
	)
	(layers
		(0 "F.Cu" signal "TOP")
		(4 "In1.Cu" signal "GND")
		(6 "In2.Cu" signal "IN1")
		(8 "In3.Cu" signal "GND1")
		(10 "In4.Cu" signal "IN2")
		(12 "In5.Cu" signal "GND2")
		(14 "In6.Cu" signal "IN3")
		(16 "In7.Cu" signal "GND3")
		(18 "In8.Cu" signal "VCC")
		(20 "In9.Cu" signal "VCC1")
		(22 "In10.Cu" signal "GND4")
		(24 "In11.Cu" signal "IN4")
		(26 "In12.Cu" signal "GND5")
		(28 "In13.Cu" signal "IN5")
		(30 "In14.Cu" signal "GND6")
		(32 "In15.Cu" signal "IN6")
		(34 "In16.Cu" signal "GND7")
		(2 "B.Cu" signal "BOTTOM")
		(9 "F.Adhes" user "F.Adhesive")
		(11 "B.Adhes" user "B.Adhesive")
		(13 "F.Paste" user "Package Geometry/Pastemask Top")
		(15 "B.Paste" user "Package Geometry/Pastemask Bottom")
		(5 "F.SilkS" user "Ref Des/Silkscreen Top")
		(7 "B.SilkS" user "Ref Des/Silkscreen Bottom")
		(1 "F.Mask" user "Board Geometry/Soldermask Top")
		(3 "B.Mask" user "Board Geometry/Soldermask Bottom")
		(17 "Dwgs.User" user "User.Drawings")
		(19 "Cmts.User" user "User.Comments")
		(21 "Eco1.User" user "User.Eco1")
		(23 "Eco2.User" user "User.Eco2")
		(25 "Edge.Cuts" user "Board Geometry/Outline")
		(27 "Margin" user)
		(31 "F.CrtYd" user "Package Geometry/Place Bound Top")
		(29 "B.CrtYd" user "Package Geometry/Place Bound Bottom")
		(35 "F.Fab" user "Ref Des/Assembly Top")
		(33 "B.Fab" user "Ref Des/Assembly Bottom")
	)
	(footprint ""
		(layer "F.Cu")
		(at 390.162542 -416.899344 -90)
		(property "Reference" "C6577"
			(at 0 0 270)
			(layer "F.SilkS")
			(hide yes)
			(effects
				(font
					(size 1.27 1.27)
				)
			)
		)
		(property "Value" ""
			(at 0 0 270)
			(layer "F.Fab")
			(effects
				(font
					(size 1.27 1.27)
				)
			)
		)
		(duplicate_pad_numbers_are_jumpers no)
		(fp_line
			(start -0.299974 0.150114)
			(end -0.299974 -0.150114)
			(stroke
				(width 0.1)
				(type default)
			)
			(layer "F.Fab")
		)
		(fp_line
			(start 0.299974 0.150114)
			(end -0.299974 0.150114)
			(stroke
				(width 0.1)
				(type default)
			)
			(layer "F.Fab")
		)
		(fp_line
			(start -0.299974 -0.150114)
			(end 0.299974 -0.150114)
			(stroke
				(width 0.1)
				(type default)
			)
			(layer "F.Fab")
		)
		(fp_line
			(start 0.299974 -0.150114)
			(end 0.299974 0.150114)
			(stroke
				(width 0.1)
				(type default)
			)
			(layer "F.Fab")
		)
		(pad "1" smd rect
			(at -0.2667 0 270)
			(size 0.3048 0.381)
			(layers "F.Cu" "F.Mask" "F.Paste")
			(net "P5E_CPU0_P2_TX_BUF_C_DP<6>")
		)
		(pad "2" smd rect
			(at 0.2667 0 270)
			(size 0.3048 0.381)
			(layers "F.Cu" "F.Mask" "F.Paste")
			(net "P5E_CPU0_P2_TX_BUF_DP<6>")
		)
	)
	(footprint ""
		(layer "F.Cu")
		(at 99.278186 -31.847536 -90)
		(property "Reference" "R6333"
			(at 0 0 270)
			(layer "F.SilkS")
			(hide yes)
			(effects
				(font
					(size 1.27 1.27)
				)
			)
		)
		(property "Value" ""
			(at 0 0 270)
			(layer "F.Fab")
			(effects
				(font
					(size 1.27 1.27)
				)
			)
		)
		(duplicate_pad_numbers_are_jumpers no)
		(fp_line
			(start -0.7874 0.4064)
			(end -0.7874 -0.4064)
			(stroke
				(width 0.1524)
				(type default)
			)
			(layer "F.SilkS")
		)
		(fp_line
			(start 0.7874 0.4064)
			(end -0.7874 0.4064)
			(stroke
				(width 0.1524)
				(type default)
			)
			(layer "F.SilkS")
		)
		(fp_line
			(start -0.7874 -0.4064)
			(end 0.7874 -0.4064)
			(stroke
				(width 0.1524)
				(type default)
			)
			(layer "F.SilkS")
		)
		(fp_line
			(start 0.7874 -0.4064)
			(end 0.7874 0.4064)
			(stroke
				(width 0.1524)
				(type default)
			)
			(layer "F.SilkS")
		)
		(fp_line
			(start -0.67945 0.3048)
			(end -0.67945 -0.305054)
			(stroke
				(width 0.1)
				(type default)
			)
			(layer "F.Fab")
		)
		(fp_line
			(start -0.12065 0.3048)
			(end -0.67945 0.3048)
			(stroke
				(width 0.1)
				(type default)
			)
			(layer "F.Fab")
		)
		(fp_line
			(start 0.120396 0.3048)
			(end 0.120396 0.2794)
			(stroke
				(width 0.1)
				(type default)
			)
			(layer "F.Fab")
		)
		(fp_line
			(start 0.67945 0.3048)
			(end 0.120396 0.3048)
			(stroke
				(width 0.1)
				(type default)
			)
			(layer "F.Fab")
		)
		(fp_line
			(start -0.12065 0.2794)
			(end -0.12065 0.3048)
			(stroke
				(width 0.1)
				(type default)
			)
			(layer "F.Fab")
		)
		(fp_line
			(start 0.120396 0.2794)
			(end -0.12065 0.2794)
			(stroke
				(width 0.1)
				(type default)
			)
			(layer "F.Fab")
		)
		(fp_line
			(start -0.12065 -0.2794)
			(end 0.12065 -0.2794)
			(stroke
				(width 0.1)
				(type default)
			)
			(layer "F.Fab")
		)
		(fp_line
			(start 0.12065 -0.2794)
			(end 0.12065 -0.3048)
			(stroke
				(width 0.1)
				(type default)
			)
			(layer "F.Fab")
		)
		(fp_line
			(start 0.12065 -0.3048)
			(end 0.67945 -0.3048)
			(stroke
				(width 0.1)
				(type default)
			)
			(layer "F.Fab")
		)
		(fp_line
			(start 0.67945 -0.3048)
			(end 0.67945 0.3048)
			(stroke
				(width 0.1)
				(type default)
			)
			(layer "F.Fab")
		)
		(fp_line
			(start -0.67945 -0.305054)
			(end -0.12065 -0.305054)
			(stroke
				(width 0.1)
				(type default)
			)
			(layer "F.Fab")
		)
		(fp_line
			(start -0.12065 -0.305054)
			(end -0.12065 -0.2794)
			(stroke
				(width 0.1)
				(type default)
			)
			(layer "F.Fab")
		)
		(pad "1" smd circle
			(at -0.40005 0 270)
			(size 0 0)
			(layers "F.Cu" "F.Mask" "F.Paste")
			(net "USB_HUB2_TI_GRSTZ_MRP_PROG_FUNC1")
		)
		(pad "2" smd circle
			(at 0.40005 0 270)
			(size 0 0)
			(layers "F.Cu" "F.Mask" "F.Paste")
			(net "GND")
		)
	)
	(footprint ""
		(layer "F.Cu")
		(at 309.894986 -416.899344 -90)
		(property "Reference" "C6506"
			(at 0 0 270)
			(layer "F.SilkS")
			(hide yes)
			(effects
				(font
					(size 1.27 1.27)
				)
			)
		)
		(property "Value" ""
			(at 0 0 270)
			(layer "F.Fab")
			(effects
				(font
					(size 1.27 1.27)
				)
			)
		)
		(duplicate_pad_numbers_are_jumpers no)
		(fp_line
			(start -0.299974 0.150114)
			(end -0.299974 -0.150114)
			(stroke
				(width 0.1)
				(type default)
			)
			(layer "F.Fab")
		)
		(fp_line
			(start 0.299974 0.150114)
			(end -0.299974 0.150114)
			(stroke
				(width 0.1)
				(type default)
			)
			(layer "F.Fab")
		)
		(fp_line
			(start -0.299974 -0.150114)
			(end 0.299974 -0.150114)
			(stroke
				(width 0.1)
				(type default)
			)
			(layer "F.Fab")
		)
		(fp_line
			(start 0.299974 -0.150114)
			(end 0.299974 0.150114)
			(stroke
				(width 0.1)
				(type default)
			)
			(layer "F.Fab")
		)
		(pad "1" smd rect
			(at -0.2667 0 270)
			(size 0.3048 0.381)
			(layers "F.Cu" "F.Mask" "F.Paste")
			(net "P5E_CPU0_P0_TX_BUF_C_DN<2>")
		)
		(pad "2" smd rect
			(at 0.2667 0 270)
			(size 0.3048 0.381)
			(layers "F.Cu" "F.Mask" "F.Paste")
			(net "P5E_CPU0_P0_TX_BUF_DN<2>")
		)
	)
	(footprint ""
		(layer "F.Cu")
		(at 333.376524 -24.771858 -90)
		(property "Reference" "C5032"
			(at 0 0 270)
			(layer "F.SilkS")
			(hide yes)
			(effects
				(font
					(size 1.27 1.27)
				)
			)
		)
		(property "Value" ""
			(at 0 0 270)
			(layer "F.Fab")
			(effects
				(font
					(size 1.27 1.27)
				)
			)
		)
		(duplicate_pad_numbers_are_jumpers no)
		(fp_line
			(start -1.524 0.762)
			(end -1.524 -0.762)
			(stroke
				(width 0.1524)
				(type default)
			)
			(layer "F.SilkS")
		)
		(fp_line
			(start 1.524 0.762)
			(end -1.524 0.762)
			(stroke
				(width 0.1524)
				(type default)
			)
			(layer "F.SilkS")
		)
		(fp_line
			(start -1.524 -0.762)
			(end 1.524 -0.762)
			(stroke
				(width 0.1524)
				(type default)
			)
			(layer "F.SilkS")
		)
		(fp_line
			(start 1.524 -0.762)
			(end 1.524 0.762)
			(stroke
				(width 0.1524)
				(type default)
			)
			(layer "F.SilkS")
		)
		(fp_line
			(start -1.1049 0.724916)
			(end 1.1049 0.724916)
			(stroke
				(width 0.1)
				(type default)
			)
			(layer "F.Fab")
		)
		(fp_line
			(start 1.1049 0.724916)
			(end 1.1049 -0.724916)
			(stroke
				(width 0.1)
				(type default)
			)
			(layer "F.Fab")
		)
		(fp_line
			(start -1.1049 -0.724916)
			(end -1.1049 0.724916)
			(stroke
				(width 0.1)
				(type default)
			)
			(layer "F.Fab")
		)
		(fp_line
			(start 1.1049 -0.724916)
			(end -1.1049 -0.724916)
			(stroke
				(width 0.1)
				(type default)
			)
			(layer "F.Fab")
		)
		(pad "1" smd rect
			(at -0.889 0 90)
			(size 1.016 1.27)
			(layers "F.Cu" "F.Mask" "F.Paste")
			(net "P1V5_BAT")
		)
		(pad "2" smd rect
			(at 0.889 0 90)
			(size 1.016 1.27)
			(layers "F.Cu" "F.Mask" "F.Paste")
			(net "GND")
		)
	)
)
